(kicad_pcb
	(version 20260206)
	(generator "pcbnew")
	(generator_version "10.0")
	(general
		(thickness 1.6)
		(legacy_teardrops no)
	)
	(paper "A4")
	(title_block
		(title "04192023_DAF0TMB3IC0_F0TG_MB_C_brd_V02_OCP.brd")
		(comment 1 "Grand Teton / footprints 92-98 of 8354")
	)
	(layers
		(0 "F.Cu" signal "TOP")
		(4 "In1.Cu" signal "GND")
		(6 "In2.Cu" signal "IN1")
		(8 "In3.Cu" signal "GND1")
		(10 "In4.Cu" signal "IN2")
		(12 "In5.Cu" signal "GND2")
		(14 "In6.Cu" signal "IN3")
		(16 "In7.Cu" signal "GND3")
		(18 "In8.Cu" signal "VCC")
		(20 "In9.Cu" signal "VCC1")
		(22 "In10.Cu" signal "GND4")
		(24 "In11.Cu" signal "IN4")
		(26 "In12.Cu" signal "GND5")
		(28 "In13.Cu" signal "IN5")
		(30 "In14.Cu" signal "GND6")
		(32 "In15.Cu" signal "IN6")
		(34 "In16.Cu" signal "GND7")
		(2 "B.Cu" signal "BOTTOM")
		(9 "F.Adhes" user "F.Adhesive")
		(11 "B.Adhes" user "B.Adhesive")
		(13 "F.Paste" user "Package Geometry/Pastemask Top")
		(15 "B.Paste" user "Package Geometry/Pastemask Bottom")
		(5 "F.SilkS" user "Ref Des/Silkscreen Top")
		(7 "B.SilkS" user "Ref Des/Silkscreen Bottom")
		(1 "F.Mask" user "Board Geometry/Soldermask Top")
		(3 "B.Mask" user "Board Geometry/Soldermask Bottom")
		(17 "Dwgs.User" user "User.Drawings")
		(19 "Cmts.User" user "User.Comments")
		(21 "Eco1.User" user "User.Eco1")
		(23 "Eco2.User" user "User.Eco2")
		(25 "Edge.Cuts" user "Board Geometry/Outline")
		(27 "Margin" user)
		(31 "F.CrtYd" user "Package Geometry/Place Bound Top")
		(29 "B.CrtYd" user "Package Geometry/Place Bound Bottom")
		(35 "F.Fab" user "Ref Des/Assembly Top")
		(33 "B.Fab" user "Ref Des/Assembly Bottom")
	)
	(footprint ""
		(layer "F.Cu")
		(at 44.069 -437.134)
		(property "Reference" "R2936"
			(at 0 0 0)
			(layer "F.SilkS")
			(hide yes)
			(effects
				(font
					(size 1.27 1.27)
				)
			)
		)
		(property "Value" ""
			(at 0 0 0)
			(layer "F.Fab")
			(effects
				(font
					(size 1.27 1.27)
				)
			)
		)
		(duplicate_pad_numbers_are_jumpers no)
		(fp_line
			(start -0.7874 -0.4064)
			(end 0.7874 -0.4064)
			(stroke
				(width 0.1524)
				(type default)
			)
			(layer "F.SilkS")
		)
		(fp_line
			(start -0.7874 0.4064)
			(end -0.7874 -0.4064)
			(stroke
				(width 0.1524)
				(type default)
			)
			(layer "F.SilkS")
		)
		(fp_line
			(start 0.7874 -0.4064)
			(end 0.7874 0.4064)
			(stroke
				(width 0.1524)
				(type default)
			)
			(layer "F.SilkS")
		)
		(fp_line
			(start 0.7874 0.4064)
			(end -0.7874 0.4064)
			(stroke
				(width 0.1524)
				(type default)
			)
			(layer "F.SilkS")
		)
		(fp_line
			(start -0.67945 -0.305054)
			(end -0.12065 -0.305054)
			(stroke
				(width 0.1)
				(type default)
			)
			(layer "F.Fab")
		)
		(fp_line
			(start -0.67945 0.3048)
			(end -0.67945 -0.305054)
			(stroke
				(width 0.1)
				(type default)
			)
			(layer "F.Fab")
		)
		(fp_line
			(start -0.12065 -0.305054)
			(end -0.12065 -0.2794)
			(stroke
				(width 0.1)
				(type default)
			)
			(layer "F.Fab")
		)
		(fp_line
			(start -0.12065 -0.2794)
			(end 0.12065 -0.2794)
			(stroke
				(width 0.1)
				(type default)
			)
			(layer "F.Fab")
		)
		(fp_line
			(start -0.12065 0.2794)
			(end -0.12065 0.3048)
			(stroke
				(width 0.1)
				(type default)
			)
			(layer "F.Fab")
		)
		(fp_line
			(start -0.12065 0.3048)
			(end -0.67945 0.3048)
			(stroke
				(width 0.1)
				(type default)
			)
			(layer "F.Fab")
		)
		(fp_line
			(start 0.120396 0.2794)
			(end -0.12065 0.2794)
			(stroke
				(width 0.1)
				(type default)
			)
			(layer "F.Fab")
		)
		(fp_line
			(start 0.120396 0.3048)
			(end 0.120396 0.2794)
			(stroke
				(width 0.1)
				(type default)
			)
			(layer "F.Fab")
		)
		(fp_line
			(start 0.12065 -0.3048)
			(end 0.67945 -0.3048)
			(stroke
				(width 0.1)
				(type default)
			)
			(layer "F.Fab")
		)
		(fp_line
			(start 0.12065 -0.2794)
			(end 0.12065 -0.3048)
			(stroke
				(width 0.1)
				(type default)
			)
			(layer "F.Fab")
		)
		(fp_line
			(start 0.67945 -0.3048)
			(end 0.67945 0.3048)
			(stroke
				(width 0.1)
				(type default)
			)
			(layer "F.Fab")
		)
		(fp_line
			(start 0.67945 0.3048)
			(end 0.120396 0.3048)
			(stroke
				(width 0.1)
				(type default)
			)
			(layer "F.Fab")
		)
		(pad "1" smd circle
			(at -0.40005 0)
			(size 0 0)
			(layers "F.Cu" "F.Mask" "F.Paste")
			(net "P3V3_AUX")
		)
		(pad "2" smd circle
			(at 0.40005 0)
			(size 0 0)
			(layers "F.Cu" "F.Mask" "F.Paste")
			(net "FM_GPU_PWR_EN_R")
		)
	)
	(footprint ""
		(layer "F.Cu")
		(at 173.216062 -29.430472)
		(property "Reference" "R3836"
			(at 0 0 0)
			(layer "F.SilkS")
			(hide yes)
			(effects
				(font
					(size 1.27 1.27)
				)
			)
		)
		(property "Value" ""
			(at 0 0 0)
			(layer "F.Fab")
			(effects
				(font
					(size 1.27 1.27)
				)
			)
		)
		(duplicate_pad_numbers_are_jumpers no)
		(fp_line
			(start -0.7874 -0.4064)
			(end 0.7874 -0.4064)
			(stroke
				(width 0.1524)
				(type default)
			)
			(layer "F.SilkS")
		)
		(fp_line
			(start -0.7874 0.4064)
			(end -0.7874 -0.4064)
			(stroke
				(width 0.1524)
				(type default)
			)
			(layer "F.SilkS")
		)
		(fp_line
			(start 0.7874 -0.4064)
			(end 0.7874 0.4064)
			(stroke
				(width 0.1524)
				(type default)
			)
			(layer "F.SilkS")
		)
		(fp_line
			(start 0.7874 0.4064)
			(end -0.7874 0.4064)
			(stroke
				(width 0.1524)
				(type default)
			)
			(layer "F.SilkS")
		)
		(fp_line
			(start -0.67945 -0.305054)
			(end -0.12065 -0.305054)
			(stroke
				(width 0.1)
				(type default)
			)
			(layer "F.Fab")
		)
		(fp_line
			(start -0.67945 0.3048)
			(end -0.67945 -0.305054)
			(stroke
				(width 0.1)
				(type default)
			)
			(layer "F.Fab")
		)
		(fp_line
			(start -0.12065 -0.305054)
			(end -0.12065 -0.2794)
			(stroke
				(width 0.1)
				(type default)
			)
			(layer "F.Fab")
		)
		(fp_line
			(start -0.12065 -0.2794)
			(end 0.12065 -0.2794)
			(stroke
				(width 0.1)
				(type default)
			)
			(layer "F.Fab")
		)
		(fp_line
			(start -0.12065 0.2794)
			(end -0.12065 0.3048)
			(stroke
				(width 0.1)
				(type default)
			)
			(layer "F.Fab")
		)
		(fp_line
			(start -0.12065 0.3048)
			(end -0.67945 0.3048)
			(stroke
				(width 0.1)
				(type default)
			)
			(layer "F.Fab")
		)
		(fp_line
			(start 0.120396 0.2794)
			(end -0.12065 0.2794)
			(stroke
				(width 0.1)
				(type default)
			)
			(layer "F.Fab")
		)
		(fp_line
			(start 0.120396 0.3048)
			(end 0.120396 0.2794)
			(stroke
				(width 0.1)
				(type default)
			)
			(layer "F.Fab")
		)
		(fp_line
			(start 0.12065 -0.3048)
			(end 0.67945 -0.3048)
			(stroke
				(width 0.1)
				(type default)
			)
			(layer "F.Fab")
		)
		(fp_line
			(start 0.12065 -0.2794)
			(end 0.12065 -0.3048)
			(stroke
				(width 0.1)
				(type default)
			)
			(layer "F.Fab")
		)
		(fp_line
			(start 0.67945 -0.3048)
			(end 0.67945 0.3048)
			(stroke
				(width 0.1)
				(type default)
			)
			(layer "F.Fab")
		)
		(fp_line
			(start 0.67945 0.3048)
			(end 0.120396 0.3048)
			(stroke
				(width 0.1)
				(type default)
			)
			(layer "F.Fab")
		)
		(pad "1" smd circle
			(at -0.40005 0)
			(size 0 0)
			(layers "F.Cu" "F.Mask" "F.Paste")
			(net "P3V3_AUX")
		)
		(pad "2" smd circle
			(at 0.40005 0)
			(size 0 0)
			(layers "F.Cu" "F.Mask" "F.Paste")
			(net "HP_LVC3_SCM_HSC_PWRGD_R")
		)
	)
	(footprint ""
		(layer "F.Cu")
		(at 405.42464 -381.41783 -90)
		(property "Reference" "C859"
			(at 0 0 270)
			(layer "F.SilkS")
			(hide yes)
			(effects
				(font
					(size 1.27 1.27)
				)
			)
		)
		(property "Value" ""
			(at 0 0 270)
			(layer "F.Fab")
			(effects
				(font
					(size 1.27 1.27)
				)
			)
		)
		(duplicate_pad_numbers_are_jumpers no)
		(fp_line
			(start -0.299974 0.150114)
			(end -0.299974 -0.150114)
			(stroke
				(width 0.1)
				(type default)
			)
			(layer "F.Fab")
		)
		(fp_line
			(start 0.299974 0.150114)
			(end -0.299974 0.150114)
			(stroke
				(width 0.1)
				(type default)
			)
			(layer "F.Fab")
		)
		(fp_line
			(start -0.299974 -0.150114)
			(end 0.299974 -0.150114)
			(stroke
				(width 0.1)
				(type default)
			)
			(layer "F.Fab")
		)
		(fp_line
			(start 0.299974 -0.150114)
			(end 0.299974 0.150114)
			(stroke
				(width 0.1)
				(type default)
			)
			(layer "F.Fab")
		)
		(pad "1" smd rect
			(at -0.2667 0 270)
			(size 0.3048 0.381)
			(layers "F.Cu" "F.Mask" "F.Paste")
			(net "P5E_CPU0_P2_TX_C_DP<5>")
		)
		(pad "2" smd rect
			(at 0.2667 0 270)
			(size 0.3048 0.381)
			(layers "F.Cu" "F.Mask" "F.Paste")
			(net "P5E_CPU0_P2_TX_DP<5>")
		)
	)
	(footprint ""
		(layer "F.Cu")
		(at 140.250672 -392.521694)
		(property "Reference" "L8"
			(at -2.3876 -2.969768 0)
			(unlocked yes)
			(layer "F.SilkS")
			(effects
				(font
					(size 0.7874 0.5842)
					(thickness 0.1524)
				)
				(justify left)
			)
		)
		(property "Value" ""
			(at 0 0 0)
			(layer "F.Fab")
			(effects
				(font
					(size 1.27 1.27)
				)
			)
		)
		(duplicate_pad_numbers_are_jumpers no)
		(fp_line
			(start -2.249932 -2.249932)
			(end 2.249932 -2.249932)
			(stroke
				(width 0.1524)
				(type default)
			)
			(layer "F.SilkS")
		)
		(fp_line
			(start -2.249932 -1.3843)
			(end -2.249932 -2.249932)
			(stroke
				(width 0.1524)
				(type default)
			)
			(layer "F.SilkS")
		)
		(fp_line
			(start -2.249932 2.249932)
			(end -2.249932 1.3843)
			(stroke
				(width 0.1524)
				(type default)
			)
			(layer "F.SilkS")
		)
		(fp_line
			(start 2.249932 -2.249932)
			(end 2.249932 -1.3843)
			(stroke
				(width 0.1524)
				(type default)
			)
			(layer "F.SilkS")
		)
		(fp_line
			(start 2.249932 1.3843)
			(end 2.249932 2.249932)
			(stroke
				(width 0.1524)
				(type default)
			)
			(layer "F.SilkS")
		)
		(fp_line
			(start 2.249932 2.249932)
			(end -2.249932 2.249932)
			(stroke
				(width 0.1524)
				(type default)
			)
			(layer "F.SilkS")
		)
		(fp_line
			(start -2.249932 -2.249932)
			(end 2.249932 -2.249932)
			(stroke
				(width 0.1)
				(type default)
			)
			(layer "F.Fab")
		)
		(fp_line
			(start -2.249932 2.249932)
			(end -2.249932 -2.249932)
			(stroke
				(width 0.1)
				(type default)
			)
			(layer "F.Fab")
		)
		(fp_line
			(start 2.249932 -2.249932)
			(end 2.249932 2.249932)
			(stroke
				(width 0.1)
				(type default)
			)
			(layer "F.Fab")
		)
		(fp_line
			(start 2.249932 2.249932)
			(end -2.249932 2.249932)
			(stroke
				(width 0.1)
				(type default)
			)
			(layer "F.Fab")
		)
		(pad "1" smd rect
			(at -1.82499 0)
			(size 1.0668 2.5146)
			(layers "F.Cu" "F.Mask" "F.Paste")
			(net "P0V9_CPU1_RT_2D")
		)
		(pad "2" smd rect
			(at 1.82499 0)
			(size 1.0668 2.5146)
			(layers "F.Cu" "F.Mask" "F.Paste")
			(net "P0V9_CPU1_RT2_2A")
		)
	)
	(footprint ""
		(layer "F.Cu")
		(at 183.6547 -406.636982 90)
		(property "Reference" "PC2189"
			(at 0 0 90)
			(layer "F.SilkS")
			(hide yes)
			(effects
				(font
					(size 1.27 1.27)
				)
			)
		)
		(property "Value" ""
			(at 0 0 90)
			(layer "F.Fab")
			(effects
				(font
					(size 1.27 1.27)
				)
			)
		)
		(duplicate_pad_numbers_are_jumpers no)
		(fp_line
			(start 0.7874 -0.4064)
			(end 0.7874 0.4064)
			(stroke
				(width 0.1524)
				(type default)
			)
			(layer "F.SilkS")
		)
		(fp_line
			(start -0.7874 -0.4064)
			(end 0.7874 -0.4064)
			(stroke
				(width 0.1524)
				(type default)
			)
			(layer "F.SilkS")
		)
		(fp_line
			(start 0.7874 0.4064)
			(end -0.7874 0.4064)
			(stroke
				(width 0.1524)
				(type default)
			)
			(layer "F.SilkS")
		)
		(fp_line
			(start -0.7874 0.4064)
			(end -0.7874 -0.4064)
			(stroke
				(width 0.1524)
				(type default)
			)
			(layer "F.SilkS")
		)
		(fp_line
			(start -0.12065 -0.305054)
			(end -0.12065 -0.2794)
			(stroke
				(width 0.1)
				(type default)
			)
			(layer "F.Fab")
		)
		(fp_line
			(start -0.67945 -0.305054)
			(end -0.12065 -0.305054)
			(stroke
				(width 0.1)
				(type default)
			)
			(layer "F.Fab")
		)
		(fp_line
			(start 0.67945 -0.3048)
			(end 0.67945 0.3048)
			(stroke
				(width 0.1)
				(type default)
			)
			(layer "F.Fab")
		)
		(fp_line
			(start 0.12065 -0.3048)
			(end 0.67945 -0.3048)
			(stroke
				(width 0.1)
				(type default)
			)
			(layer "F.Fab")
		)
		(fp_line
			(start 0.12065 -0.2794)
			(end 0.12065 -0.3048)
			(stroke
				(width 0.1)
				(type default)
			)
			(layer "F.Fab")
		)
		(fp_line
			(start -0.12065 -0.2794)
			(end 0.12065 -0.2794)
			(stroke
				(width 0.1)
				(type default)
			)
			(layer "F.Fab")
		)
		(fp_line
			(start 0.120396 0.2794)
			(end -0.12065 0.2794)
			(stroke
				(width 0.1)
				(type default)
			)
			(layer "F.Fab")
		)
		(fp_line
			(start -0.12065 0.2794)
			(end -0.12065 0.3048)
			(stroke
				(width 0.1)
				(type default)
			)
			(layer "F.Fab")
		)
		(fp_line
			(start 0.67945 0.3048)
			(end 0.120396 0.3048)
			(stroke
				(width 0.1)
				(type default)
			)
			(layer "F.Fab")
		)
		(fp_line
			(start 0.120396 0.3048)
			(end 0.120396 0.2794)
			(stroke
				(width 0.1)
				(type default)
			)
			(layer "F.Fab")
		)
		(fp_line
			(start -0.12065 0.3048)
			(end -0.67945 0.3048)
			(stroke
				(width 0.1)
				(type default)
			)
			(layer "F.Fab")
		)
		(fp_line
			(start -0.67945 0.3048)
			(end -0.67945 -0.305054)
			(stroke
				(width 0.1)
				(type default)
			)
			(layer "F.Fab")
		)
		(pad "1" smd circle
			(at -0.40005 0 90)
			(size 0 0)
			(layers "F.Cu" "F.Mask" "F.Paste")
			(net "HSC_VSENSE")
		)
		(pad "2" smd circle
			(at 0.40005 0 90)
			(size 0 0)
			(layers "F.Cu" "F.Mask" "F.Paste")
			(net "AGND_HSC")
		)
	)
	(footprint ""
		(layer "F.Cu")
		(at 140.420344 -39.793418 180)
		(property "Reference" "R6208"
			(at 0 0 180)
			(layer "F.SilkS")
			(hide yes)
			(effects
				(font
					(size 1.27 1.27)
				)
			)
		)
		(property "Value" ""
			(at 0 0 180)
			(layer "F.Fab")
			(effects
				(font
					(size 1.27 1.27)
				)
			)
		)
		(duplicate_pad_numbers_are_jumpers no)
		(fp_line
			(start 0.7874 0.4064)
			(end -0.7874 0.4064)
			(stroke
				(width 0.1524)
				(type default)
			)
			(layer "F.SilkS")
		)
		(fp_line
			(start 0.7874 -0.4064)
			(end 0.7874 0.4064)
			(stroke
				(width 0.1524)
				(type default)
			)
			(layer "F.SilkS")
		)
		(fp_line
			(start -0.7874 0.4064)
			(end -0.7874 -0.4064)
			(stroke
				(width 0.1524)
				(type default)
			)
			(layer "F.SilkS")
		)
		(fp_line
			(start -0.7874 -0.4064)
			(end 0.7874 -0.4064)
			(stroke
				(width 0.1524)
				(type default)
			)
			(layer "F.SilkS")
		)
		(fp_line
			(start 0.67945 0.3048)
			(end 0.120396 0.3048)
			(stroke
				(width 0.1)
				(type default)
			)
			(layer "F.Fab")
		)
		(fp_line
			(start 0.67945 -0.3048)
			(end 0.67945 0.3048)
			(stroke
				(width 0.1)
				(type default)
			)
			(layer "F.Fab")
		)
		(fp_line
			(start 0.12065 -0.2794)
			(end 0.12065 -0.3048)
			(stroke
				(width 0.1)
				(type default)
			)
			(layer "F.Fab")
		)
		(fp_line
			(start 0.12065 -0.3048)
			(end 0.67945 -0.3048)
			(stroke
				(width 0.1)
				(type default)
			)
			(layer "F.Fab")
		)
		(fp_line
			(start 0.120396 0.3048)
			(end 0.120396 0.2794)
			(stroke
				(width 0.1)
				(type default)
			)
			(layer "F.Fab")
		)
		(fp_line
			(start 0.120396 0.2794)
			(end -0.12065 0.2794)
			(stroke
				(width 0.1)
				(type default)
			)
			(layer "F.Fab")
		)
		(fp_line
			(start -0.12065 0.3048)
			(end -0.67945 0.3048)
			(stroke
				(width 0.1)
				(type default)
			)
			(layer "F.Fab")
		)
		(fp_line
			(start -0.12065 0.2794)
			(end -0.12065 0.3048)
			(stroke
				(width 0.1)
				(type default)
			)
			(layer "F.Fab")
		)
		(fp_line
			(start -0.12065 -0.2794)
			(end 0.12065 -0.2794)
			(stroke
				(width 0.1)
				(type default)
			)
			(layer "F.Fab")
		)
		(fp_line
			(start -0.12065 -0.305054)
			(end -0.12065 -0.2794)
			(stroke
				(width 0.1)
				(type default)
			)
			(layer "F.Fab")
		)
		(fp_line
			(start -0.67945 0.3048)
			(end -0.67945 -0.305054)
			(stroke
				(width 0.1)
				(type default)
			)
			(layer "F.Fab")
		)
		(fp_line
			(start -0.67945 -0.305054)
			(end -0.12065 -0.305054)
			(stroke
				(width 0.1)
				(type default)
			)
			(layer "F.Fab")
		)
		(pad "1" smd circle
			(at -0.40005 0 180)
			(size 0 0)
			(layers "F.Cu" "F.Mask" "F.Paste")
			(net "P5V_AUX")
		)
		(pad "2" smd circle
			(at 0.40005 0 180)
			(size 0 0)
			(layers "F.Cu" "F.Mask" "F.Paste")
			(net "USB_CPU0_HUB1_VBUS_US")
		)
	)
	(footprint ""
		(layer "F.Cu")
		(at 386.211826 -53.1495 180)
		(property "Reference" "R1352"
			(at 0 0 180)
			(layer "F.SilkS")
			(hide yes)
			(effects
				(font
					(size 1.27 1.27)
				)
			)
		)
		(property "Value" ""
			(at 0 0 180)
			(layer "F.Fab")
			(effects
				(font
					(size 1.27 1.27)
				)
			)
		)
		(duplicate_pad_numbers_are_jumpers no)
		(fp_line
			(start 0.7874 0.4064)
			(end -0.7874 0.4064)
			(stroke
				(width 0.1524)
				(type default)
			)
			(layer "F.SilkS")
		)
		(fp_line
			(start 0.7874 -0.4064)
			(end 0.7874 0.4064)
			(stroke
				(width 0.1524)
				(type default)
			)
			(layer "F.SilkS")
		)
		(fp_line
			(start -0.7874 0.4064)
			(end -0.7874 -0.4064)
			(stroke
				(width 0.1524)
				(type default)
			)
			(layer "F.SilkS")
		)
		(fp_line
			(start -0.7874 -0.4064)
			(end 0.7874 -0.4064)
			(stroke
				(width 0.1524)
				(type default)
			)
			(layer "F.SilkS")
		)
		(fp_line
			(start 0.67945 0.3048)
			(end 0.120396 0.3048)
			(stroke
				(width 0.1)
				(type default)
			)
			(layer "F.Fab")
		)
		(fp_line
			(start 0.67945 -0.3048)
			(end 0.67945 0.3048)
			(stroke
				(width 0.1)
				(type default)
			)
			(layer "F.Fab")
		)
		(fp_line
			(start 0.12065 -0.2794)
			(end 0.12065 -0.3048)
			(stroke
				(width 0.1)
				(type default)
			)
			(layer "F.Fab")
		)
		(fp_line
			(start 0.12065 -0.3048)
			(end 0.67945 -0.3048)
			(stroke
				(width 0.1)
				(type default)
			)
			(layer "F.Fab")
		)
		(fp_line
			(start 0.120396 0.3048)
			(end 0.120396 0.2794)
			(stroke
				(width 0.1)
				(type default)
			)
			(layer "F.Fab")
		)
		(fp_line
			(start 0.120396 0.2794)
			(end -0.12065 0.2794)
			(stroke
				(width 0.1)
				(type default)
			)
			(layer "F.Fab")
		)
		(fp_line
			(start -0.12065 0.3048)
			(end -0.67945 0.3048)
			(stroke
				(width 0.1)
				(type default)
			)
			(layer "F.Fab")
		)
		(fp_line
			(start -0.12065 0.2794)
			(end -0.12065 0.3048)
			(stroke
				(width 0.1)
				(type default)
			)
			(layer "F.Fab")
		)
		(fp_line
			(start -0.12065 -0.2794)
			(end 0.12065 -0.2794)
			(stroke
				(width 0.1)
				(type default)
			)
			(layer "F.Fab")
		)
		(fp_line
			(start -0.12065 -0.305054)
			(end -0.12065 -0.2794)
			(stroke
				(width 0.1)
				(type default)
			)
			(layer "F.Fab")
		)
		(fp_line
			(start -0.67945 0.3048)
			(end -0.67945 -0.305054)
			(stroke
				(width 0.1)
				(type default)
			)
			(layer "F.Fab")
		)
		(fp_line
			(start -0.67945 -0.305054)
			(end -0.12065 -0.305054)
			(stroke
				(width 0.1)
				(type default)
			)
			(layer "F.Fab")
		)
		(pad "1" smd circle
			(at -0.40005 0 180)
			(size 0 0)
			(layers "F.Cu" "F.Mask" "F.Paste")
			(net "HDT_HDR_R_TCK")
		)
		(pad "2" smd circle
			(at 0.40005 0 180)
			(size 0 0)
			(layers "F.Cu" "F.Mask" "F.Paste")
			(net "HDT_HDR_TCK")
		)
	)
)
